# BASEBOARD_FAB2 (Tioga Pass) — schematic netlist excerpt (pin names and nets, part order shuffled) for the footprints in the layout excerpt that follows; sources: Cadence DE-HDL packaged netlist, KiCad conversion of Wiwynn_Tioga_Pass_MB.brd

C25W14  CAP_A  0.1UF 16V 10% X7R  pkg 0402V  page 151 : A = P2V5_AUX_BMC ; B = GND
C9W8  CAP_A  0.1UF 16V 10% X7R  pkg 0402V  page 248 : A = PVCCIO_CPU0 ; B = GND
C7A20  CAP_A  0.1UF 16V 10% X7R  pkg 0402V  page 219 : A = VR_FET_SW_P12V_STBY_PVDDQ_DEF ; B = GND

(kicad_pcb
	(version 20260206)
	(generator "pcbnew")
	(generator_version "10.0")
	(general
		(thickness 1.6)
		(legacy_teardrops no)
	)
	(paper "A4")
	(title_block
		(title "Wiwynn_Tioga_Pass_MB.brd")
		(comment 1 "Tioga Pass / footprints 581-583 of 4770")
	)
	(layers
		(0 "F.Cu" signal "TOP")
		(4 "In1.Cu" signal "L2GND")
		(6 "In2.Cu" signal "L3")
		(8 "In3.Cu" signal "L4GND")
		(10 "In4.Cu" signal "L5")
		(12 "In5.Cu" signal "L6GND")
		(14 "In6.Cu" signal "L7VCC")
		(16 "In7.Cu" signal "L8VCC")
		(18 "In8.Cu" signal "L9GND")
		(20 "In9.Cu" signal "L10")
		(22 "In10.Cu" signal "L11GND")
		(24 "In11.Cu" signal "L12")
		(26 "In12.Cu" signal "L13GND")
		(2 "B.Cu" signal "BOTTOM")
		(9 "F.Adhes" user "F.Adhesive")
		(11 "B.Adhes" user "B.Adhesive")
		(13 "F.Paste" user "Package Geometry/Pastemask Top")
		(15 "B.Paste" user "Package Geometry/Pastemask Bottom")
		(5 "F.SilkS" user "Ref Des/Silkscreen Top")
		(7 "B.SilkS" user "Ref Des/Silkscreen Bottom")
		(1 "F.Mask" user "Board Geometry/Soldermask Top")
		(3 "B.Mask" user "Board Geometry/Soldermask Bottom")
		(17 "Dwgs.User" user "User.Drawings")
		(19 "Cmts.User" user "User.Comments")
		(21 "Eco1.User" user "User.Eco1")
		(23 "Eco2.User" user "User.Eco2")
		(25 "Edge.Cuts" user "Board Geometry/Outline")
		(27 "Margin" user)
		(31 "F.CrtYd" user "Package Geometry/Place Bound Top")
		(29 "B.CrtYd" user "Package Geometry/Place Bound Bottom")
		(35 "F.Fab" user "Ref Des/Assembly Top")
		(33 "B.Fab" user "Ref Des/Assembly Bottom")
	)
	(footprint ""
		(layer "F.Cu")
		(at 347.988636 -141.454378 -90)
		(property "Reference" "C7A20"
			(at 0 0 270)
			(layer "F.SilkS")
			(hide yes)
			(effects
				(font
					(size 1.27 1.27)
				)
			)
		)
		(property "Value" ""
			(at 0 0 270)
			(layer "F.Fab")
			(effects
				(font
					(size 1.27 1.27)
				)
			)
		)
		(duplicate_pad_numbers_are_jumpers no)
		(fp_poly
			(pts
				(xy 0.3048 -0.1016) (xy 0.3048 0.9906) (xy -0.3048 0.9906) (xy -0.3048 -0.1016)
			)
			(stroke
				(width 0)
				(type default)
			)
			(fill no)
			(layer "F.CrtYd")
		)
		(fp_line
			(start -0.3048 0.9906)
			(end 0.3048 0.9906)
			(stroke
				(width 0.1)
				(type default)
			)
			(layer "F.Fab")
		)
		(fp_line
			(start 0.3048 0.9906)
			(end 0.3048 -0.1016)
			(stroke
				(width 0.1)
				(type default)
			)
			(layer "F.Fab")
		)
		(fp_line
			(start -0.3048 -0.1016)
			(end -0.3048 0.9906)
			(stroke
				(width 0.1)
				(type default)
			)
			(layer "F.Fab")
		)
		(fp_line
			(start 0.3048 -0.1016)
			(end -0.3048 -0.1016)
			(stroke
				(width 0.1)
				(type default)
			)
			(layer "F.Fab")
		)
		(pad "1" smd rect
			(at 0 0 270)
			(size 0.508 0.508)
			(layers "F.Cu" "F.Mask" "F.Paste")
			(net "VR_FET_SW_P12V_STBY_PVDDQ_DEF")
		)
		(pad "2" smd rect
			(at 0 0.889 270)
			(size 0.508 0.508)
			(layers "F.Cu" "F.Mask" "F.Paste")
			(net "GND")
		)
		(zone
			(layer "F.Cu")
			(hatch none 0.5)
			(connect_pads
				(clearance 0)
			)
			(min_thickness 0.25)
			(keepout
				(tracks not_allowed)
				(vias allowed)
				(pads allowed)
				(copperpour not_allowed)
				(footprints allowed)
			)
			(placement
				(enabled no)
				(sheetname "")
			)
			(fill
				(thermal_gap 0.5)
				(thermal_bridge_width 0.5)
				(island_removal_mode 0)
			)
			(polygon
				(pts
					(xy 347.353636 -141.708378) (xy 347.353636 -141.200378) (xy 347.734636 -141.200378) (xy 347.734636 -141.708378)
				)
			)
		)
		(zone
			(layer "F.Cu")
			(hatch none 0.5)
			(connect_pads
				(clearance 0)
			)
			(min_thickness 0.25)
			(keepout
				(tracks allowed)
				(vias not_allowed)
				(pads allowed)
				(copperpour not_allowed)
				(footprints allowed)
			)
			(placement
				(enabled no)
				(sheetname "")
			)
			(fill
				(thermal_gap 0.5)
				(thermal_bridge_width 0.5)
				(island_removal_mode 0)
			)
			(polygon
				(pts
					(xy 347.734636 -141.708378) (xy 347.734636 -141.200378) (xy 347.353636 -141.200378) (xy 347.353636 -141.708378)
				)
			)
		)
	)
	(footprint ""
		(layer "F.Cu")
		(at 445.91732 -24.47798)
		(property "Reference" "C25W14"
			(at -0.8382 -0.67818 0)
			(unlocked yes)
			(layer "F.SilkS")
			(effects
				(font
					(size 0.4064 0.254)
					(thickness 0.1524)
				)
				(justify left)
			)
		)
		(property "Value" ""
			(at 0 0 0)
			(layer "F.Fab")
			(effects
				(font
					(size 1.27 1.27)
				)
			)
		)
		(duplicate_pad_numbers_are_jumpers no)
		(fp_poly
			(pts
				(xy 0.3048 -0.1016) (xy 0.3048 0.9906) (xy -0.3048 0.9906) (xy -0.3048 -0.1016)
			)
			(stroke
				(width 0)
				(type default)
			)
			(fill no)
			(layer "F.CrtYd")
		)
		(fp_line
			(start -0.3048 -0.1016)
			(end -0.3048 0.9906)
			(stroke
				(width 0.1)
				(type default)
			)
			(layer "F.Fab")
		)
		(fp_line
			(start -0.3048 0.9906)
			(end 0.3048 0.9906)
			(stroke
				(width 0.1)
				(type default)
			)
			(layer "F.Fab")
		)
		(fp_line
			(start 0.3048 -0.1016)
			(end -0.3048 -0.1016)
			(stroke
				(width 0.1)
				(type default)
			)
			(layer "F.Fab")
		)
		(fp_line
			(start 0.3048 0.9906)
			(end 0.3048 -0.1016)
			(stroke
				(width 0.1)
				(type default)
			)
			(layer "F.Fab")
		)
		(pad "1" smd rect
			(at 0 0)
			(size 0.508 0.508)
			(layers "F.Cu" "F.Mask" "F.Paste")
			(net "P2V5_AUX_BMC")
		)
		(pad "2" smd rect
			(at 0 0.889)
			(size 0.508 0.508)
			(layers "F.Cu" "F.Mask" "F.Paste")
			(net "GND")
		)
		(zone
			(layer "F.Cu")
			(hatch none 0.5)
			(connect_pads
				(clearance 0)
			)
			(min_thickness 0.25)
			(keepout
				(tracks allowed)
				(vias not_allowed)
				(pads allowed)
				(copperpour not_allowed)
				(footprints allowed)
			)
			(placement
				(enabled no)
				(sheetname "")
			)
			(fill
				(thermal_gap 0.5)
				(thermal_bridge_width 0.5)
				(island_removal_mode 0)
			)
			(polygon
				(pts
					(xy 445.66332 -24.22398) (xy 446.17132 -24.22398) (xy 446.17132 -23.84298) (xy 445.66332 -23.84298)
				)
			)
		)
		(zone
			(layer "F.Cu")
			(hatch none 0.5)
			(connect_pads
				(clearance 0)
			)
			(min_thickness 0.25)
			(keepout
				(tracks not_allowed)
				(vias allowed)
				(pads allowed)
				(copperpour not_allowed)
				(footprints allowed)
			)
			(placement
				(enabled no)
				(sheetname "")
			)
			(fill
				(thermal_gap 0.5)
				(thermal_bridge_width 0.5)
				(island_removal_mode 0)
			)
			(polygon
				(pts
					(xy 445.66332 -23.84298) (xy 446.17132 -23.84298) (xy 446.17132 -24.22398) (xy 445.66332 -24.22398)
				)
			)
		)
	)
	(footprint ""
		(layer "F.Cu")
		(at 417.398454 -105.34777 180)
		(property "Reference" "C9W8"
			(at -0.8382 -0.67818 180)
			(unlocked yes)
			(layer "F.SilkS")
			(effects
				(font
					(size 0.4064 0.254)
					(thickness 0.1524)
				)
				(justify left)
			)
		)
		(property "Value" ""
			(at 0 0 180)
			(layer "F.Fab")
			(effects
				(font
					(size 1.27 1.27)
				)
			)
		)
		(duplicate_pad_numbers_are_jumpers no)
		(fp_poly
			(pts
				(xy 0.3048 -0.1016) (xy 0.3048 0.9906) (xy -0.3048 0.9906) (xy -0.3048 -0.1016)
			)
			(stroke
				(width 0)
				(type default)
			)
			(fill no)
			(layer "F.CrtYd")
		)
		(fp_line
			(start 0.3048 0.9906)
			(end 0.3048 -0.1016)
			(stroke
				(width 0.1)
				(type default)
			)
			(layer "F.Fab")
		)
		(fp_line
			(start 0.3048 -0.1016)
			(end -0.3048 -0.1016)
			(stroke
				(width 0.1)
				(type default)
			)
			(layer "F.Fab")
		)
		(fp_line
			(start -0.3048 0.9906)
			(end 0.3048 0.9906)
			(stroke
				(width 0.1)
				(type default)
			)
			(layer "F.Fab")
		)
		(fp_line
			(start -0.3048 -0.1016)
			(end -0.3048 0.9906)
			(stroke
				(width 0.1)
				(type default)
			)
			(layer "F.Fab")
		)
		(pad "1" smd rect
			(at 0 0 180)
			(size 0.508 0.508)
			(layers "F.Cu" "F.Mask" "F.Paste")
			(net "PVCCIO_CPU0")
		)
		(pad "2" smd rect
			(at 0 0.889 180)
			(size 0.508 0.508)
			(layers "F.Cu" "F.Mask" "F.Paste")
			(net "GND")
		)
		(zone
			(layer "F.Cu")
			(hatch none 0.5)
			(connect_pads
				(clearance 0)
			)
			(min_thickness 0.25)
			(keepout
				(tracks not_allowed)
				(vias allowed)
				(pads allowed)
				(copperpour not_allowed)
				(footprints allowed)
			)
			(placement
				(enabled no)
				(sheetname "")
			)
			(fill
				(thermal_gap 0.5)
				(thermal_bridge_width 0.5)
				(island_removal_mode 0)
			)
			(polygon
				(pts
					(xy 417.652454 -105.98277) (xy 417.144454 -105.98277) (xy 417.144454 -105.60177) (xy 417.652454 -105.60177)
				)
			)
		)
		(zone
			(layer "F.Cu")
			(hatch none 0.5)
			(connect_pads
				(clearance 0)
			)
			(min_thickness 0.25)
			(keepout
				(tracks allowed)
				(vias not_allowed)
				(pads allowed)
				(copperpour not_allowed)
				(footprints allowed)
			)
			(placement
				(enabled no)
				(sheetname "")
			)
			(fill
				(thermal_gap 0.5)
				(thermal_bridge_width 0.5)
				(island_removal_mode 0)
			)
			(polygon
				(pts
					(xy 417.652454 -105.60177) (xy 417.144454 -105.60177) (xy 417.144454 -105.98277) (xy 417.652454 -105.98277)
				)
			)
		)
	)
)
